# S9S_MB_2U (Grand Teton) — schematic netlist excerpt (pin names and nets, part order shuffled) for the footprints in the layout excerpt that follows; sources: Cadence DE-HDL packaged netlist, KiCad conversion of 03242023_DA0F0TMBIJ0_F0T_Motherboard_J_brd_V01_OCP.brd

U31  PCA9517AD  IC  pkg SOIC8  page 236
  VCCA  = PVNN_TERM_CPU1
  SCLA  = SMB_S3M_CPU1_R_SCL
  SDAA  = SMB_S3M_CPU1_R_SDA
  GND  = GND
  ENABLE  = TP_SMB_S3M_CPU1_EN
  SDAB  = SMB_S3M_CPU1_3V3AUX_SDA
  SCLB  = SMB_S3M_CPU1_3V3AUX_SCL
  VCCB  = P3V3_AUX

(kicad_pcb
	(version 20260206)
	(generator "pcbnew")
	(generator_version "10.0")
	(general
		(thickness 1.6)
		(legacy_teardrops no)
	)
	(paper "A4")
	(title_block
		(title "03242023_DA0F0TMBIJ0_F0T_Motherboard_J_brd_V01_OCP.brd")
		(comment 1 "Grand Teton / footprints 2241-2241 of 6105")
	)
	(layers
		(0 "F.Cu" signal "TOP")
		(4 "In1.Cu" signal "GND")
		(6 "In2.Cu" signal "IN1")
		(8 "In3.Cu" signal "GND1")
		(10 "In4.Cu" signal "IN2")
		(12 "In5.Cu" signal "GND2")
		(14 "In6.Cu" signal "IN3")
		(16 "In7.Cu" signal "GND3")
		(18 "In8.Cu" signal "VCC")
		(20 "In9.Cu" signal "VCC1")
		(22 "In10.Cu" signal "GND4")
		(24 "In11.Cu" signal "IN4")
		(26 "In12.Cu" signal "GND5")
		(28 "In13.Cu" signal "IN5")
		(30 "In14.Cu" signal "GND6")
		(32 "In15.Cu" signal "IN6")
		(34 "In16.Cu" signal "GND7")
		(2 "B.Cu" signal "BOTTOM")
		(9 "F.Adhes" user "F.Adhesive")
		(11 "B.Adhes" user "B.Adhesive")
		(13 "F.Paste" user "Package Geometry/Pastemask Top")
		(15 "B.Paste" user "Package Geometry/Pastemask Bottom")
		(5 "F.SilkS" user "Ref Des/Silkscreen Top")
		(7 "B.SilkS" user "Ref Des/Silkscreen Bottom")
		(1 "F.Mask" user "Board Geometry/Soldermask Top")
		(3 "B.Mask" user "Board Geometry/Soldermask Bottom")
		(17 "Dwgs.User" user "User.Drawings")
		(19 "Cmts.User" user "User.Comments")
		(21 "Eco1.User" user "User.Eco1")
		(23 "Eco2.User" user "User.Eco2")
		(25 "Edge.Cuts" user "Board Geometry/Outline")
		(27 "Margin" user)
		(31 "F.CrtYd" user "Package Geometry/Place Bound Top")
		(29 "B.CrtYd" user "Package Geometry/Place Bound Bottom")
		(35 "F.Fab" user "Ref Des/Assembly Top")
		(33 "B.Fab" user "Ref Des/Assembly Bottom")
	)
	(footprint ""
		(layer "F.Cu")
		(at 225.933 -227.929948 90)
		(property "Reference" "U31"
			(at 0.22733 -5.08 0)
			(unlocked yes)
			(layer "F.SilkS")
			(effects
				(font
					(size 0.7874 0.5842)
					(thickness 0.1524)
				)
				(justify left)
			)
		)
		(property "Value" ""
			(at 0 0 90)
			(layer "F.Fab")
			(effects
				(font
					(size 1.27 1.27)
				)
			)
		)
		(duplicate_pad_numbers_are_jumpers no)
		(fp_line
			(start 1.4224 -2.5146)
			(end 0.4572 -2.5146)
			(stroke
				(width 0.1524)
				(type default)
			)
			(layer "F.SilkS")
		)
		(fp_line
			(start 0.4572 -2.5146)
			(end 0 -2.0574)
			(stroke
				(width 0.1524)
				(type default)
			)
			(layer "F.SilkS")
		)
		(fp_line
			(start -0.4572 -2.5146)
			(end -1.4224 -2.5146)
			(stroke
				(width 0.1524)
				(type default)
			)
			(layer "F.SilkS")
		)
		(fp_line
			(start -1.4224 -2.5146)
			(end -1.4224 2.5146)
			(stroke
				(width 0.1524)
				(type default)
			)
			(layer "F.SilkS")
		)
		(fp_line
			(start 0 -2.0574)
			(end -0.4572 -2.5146)
			(stroke
				(width 0.1524)
				(type default)
			)
			(layer "F.SilkS")
		)
		(fp_line
			(start 1.4224 2.5146)
			(end 1.4224 -2.5146)
			(stroke
				(width 0.1524)
				(type default)
			)
			(layer "F.SilkS")
		)
		(fp_line
			(start -1.4224 2.5146)
			(end 1.4224 2.5146)
			(stroke
				(width 0.1524)
				(type default)
			)
			(layer "F.SilkS")
		)
		(fp_poly
			(pts
				(xy -3.069844 -3.694938) (xy -2.307844 -3.694938) (xy -2.688844 -2.932938)
			)
			(stroke
				(width 0)
				(type default)
			)
			(fill yes)
			(layer "F.SilkS")
		)
		(fp_line
			(start 2.0066 -2.5146)
			(end -2.0066 -2.5146)
			(stroke
				(width 0.1)
				(type default)
			)
			(layer "F.Fab")
		)
		(fp_line
			(start -2.0066 -2.5146)
			(end -2.0066 -2.114804)
			(stroke
				(width 0.1)
				(type default)
			)
			(layer "F.Fab")
		)
		(fp_line
			(start -2.0066 -2.114804)
			(end -2.648712 -2.114804)
			(stroke
				(width 0.1)
				(type default)
			)
			(layer "F.Fab")
		)
		(fp_line
			(start -2.648712 -2.114804)
			(end -2.648712 2.112264)
			(stroke
				(width 0.1)
				(type default)
			)
			(layer "F.Fab")
		)
		(fp_line
			(start 2.642616 -2.112264)
			(end 2.0066 -2.112264)
			(stroke
				(width 0.1)
				(type default)
			)
			(layer "F.Fab")
		)
		(fp_line
			(start 2.0066 -2.112264)
			(end 2.0066 -2.5146)
			(stroke
				(width 0.1)
				(type default)
			)
			(layer "F.Fab")
		)
		(fp_line
			(start 2.642616 2.112264)
			(end 2.642616 -2.112264)
			(stroke
				(width 0.1)
				(type default)
			)
			(layer "F.Fab")
		)
		(fp_line
			(start 2.0066 2.112264)
			(end 2.642616 2.112264)
			(stroke
				(width 0.1)
				(type default)
			)
			(layer "F.Fab")
		)
		(fp_line
			(start -2.0066 2.112264)
			(end -2.0066 2.5146)
			(stroke
				(width 0.1)
				(type default)
			)
			(layer "F.Fab")
		)
		(fp_line
			(start -2.648712 2.112264)
			(end -2.0066 2.112264)
			(stroke
				(width 0.1)
				(type default)
			)
			(layer "F.Fab")
		)
		(fp_line
			(start 2.0066 2.5146)
			(end 2.0066 2.112264)
			(stroke
				(width 0.1)
				(type default)
			)
			(layer "F.Fab")
		)
		(fp_line
			(start -2.0066 2.5146)
			(end 2.0066 2.5146)
			(stroke
				(width 0.1)
				(type default)
			)
			(layer "F.Fab")
		)
		(fp_poly
			(pts
				(xy -3.6322 -1.869186) (xy -4.3942 -1.488186) (xy -4.3942 -2.250186)
			)
			(stroke
				(width 0)
				(type default)
			)
			(fill yes)
			(layer "F.Fab")
		)
		(pad "1" smd rect
			(at -2.6416 -1.905)
			(size 0.5588 1.7272)
			(layers "F.Cu" "F.Mask" "F.Paste")
			(net "PVNN_TERM_CPU1")
		)
		(pad "2" smd rect
			(at -2.6416 -0.635)
			(size 0.5588 1.7272)
			(layers "F.Cu" "F.Mask" "F.Paste")
			(net "SMB_S3M_CPU1_R_SCL")
		)
		(pad "3" smd rect
			(at -2.6416 0.635)
			(size 0.5588 1.7272)
			(layers "F.Cu" "F.Mask" "F.Paste")
			(net "SMB_S3M_CPU1_R_SDA")
		)
		(pad "4" smd rect
			(at -2.6416 1.905)
			(size 0.5588 1.7272)
			(layers "F.Cu" "F.Mask" "F.Paste")
			(net "GND")
		)
		(pad "5" smd rect
			(at 2.6416 1.905)
			(size 0.5588 1.7272)
			(layers "F.Cu" "F.Mask" "F.Paste")
			(net "TP_SMB_S3M_CPU1_EN")
		)
		(pad "6" smd rect
			(at 2.6416 0.635)
			(size 0.5588 1.7272)
			(layers "F.Cu" "F.Mask" "F.Paste")
			(net "SMB_S3M_CPU1_3V3AUX_SDA")
		)
		(pad "7" smd rect
			(at 2.6416 -0.635)
			(size 0.5588 1.7272)
			(layers "F.Cu" "F.Mask" "F.Paste")
			(net "SMB_S3M_CPU1_3V3AUX_SCL")
		)
		(pad "8" smd rect
			(at 2.6416 -1.905)
			(size 0.5588 1.7272)
			(layers "F.Cu" "F.Mask" "F.Paste")
			(net "P3V3_AUX")
		)
	)
)
